# BASEBOARD_FAB2 (Tioga Pass) — schematic netlist excerpt (pin names and nets, part order shuffled) for the footprints in the layout excerpt that follows; sources: Cadence DE-HDL packaged netlist, KiCad conversion of Wiwynn_Tioga_Pass_MB.brd

C7P17  CAP  47UF 4V 20% X6S  pkg 0805  page 76 : A = PVCCIO_CPU1 ; B = GND
C9G9  CAP  4700PF 50V 10% EMPTY  pkg 0402LF  page 141 : A = NIC_SER_P_MDI_3_DP ; B = NIC_MDI_MNG_RX_DP
R6N8  RES  10.0 1% CHIP  pkg 0402  page 163 : A = SMB_CPU1_PE_HP_GTL_SCL ; B = SMB_CPU1_PE_HP_GTL_R_SCL

(kicad_pcb
	(version 20260206)
	(generator "pcbnew")
	(generator_version "10.0")
	(general
		(thickness 1.6)
		(legacy_teardrops no)
	)
	(paper "A4")
	(title_block
		(title "Wiwynn_Tioga_Pass_MB.brd")
		(comment 1 "Tioga Pass / footprints 3486-3488 of 4770")
	)
	(layers
		(0 "F.Cu" signal "TOP")
		(4 "In1.Cu" signal "L2GND")
		(6 "In2.Cu" signal "L3")
		(8 "In3.Cu" signal "L4GND")
		(10 "In4.Cu" signal "L5")
		(12 "In5.Cu" signal "L6GND")
		(14 "In6.Cu" signal "L7VCC")
		(16 "In7.Cu" signal "L8VCC")
		(18 "In8.Cu" signal "L9GND")
		(20 "In9.Cu" signal "L10")
		(22 "In10.Cu" signal "L11GND")
		(24 "In11.Cu" signal "L12")
		(26 "In12.Cu" signal "L13GND")
		(2 "B.Cu" signal "BOTTOM")
		(9 "F.Adhes" user "F.Adhesive")
		(11 "B.Adhes" user "B.Adhesive")
		(13 "F.Paste" user "Package Geometry/Pastemask Top")
		(15 "B.Paste" user "Package Geometry/Pastemask Bottom")
		(5 "F.SilkS" user "Ref Des/Silkscreen Top")
		(7 "B.SilkS" user "Ref Des/Silkscreen Bottom")
		(1 "F.Mask" user "Board Geometry/Soldermask Top")
		(3 "B.Mask" user "Board Geometry/Soldermask Bottom")
		(17 "Dwgs.User" user "User.Drawings")
		(19 "Cmts.User" user "User.Comments")
		(21 "Eco1.User" user "User.Eco1")
		(23 "Eco2.User" user "User.Eco2")
		(25 "Edge.Cuts" user "Board Geometry/Outline")
		(27 "Margin" user)
		(31 "F.CrtYd" user "Package Geometry/Place Bound Top")
		(29 "B.CrtYd" user "Package Geometry/Place Bound Bottom")
		(35 "F.Fab" user "Ref Des/Assembly Top")
		(33 "B.Fab" user "Ref Des/Assembly Bottom")
	)
	(footprint ""
		(layer "B.Cu")
		(at 175.006 -88.646 180)
		(property "Reference" "R6N8"
			(at 0 0 0)
			(layer "B.SilkS")
			(hide yes)
			(effects
				(font
					(size 1.27 1.27)
				)
				(justify mirror)
			)
		)
		(property "Value" ""
			(at 0 0 0)
			(layer "B.Fab")
			(effects
				(font
					(size 1.27 1.27)
				)
				(justify mirror)
			)
		)
		(duplicate_pad_numbers_are_jumpers no)
		(fp_poly
			(pts
				(xy 0.2794 -0.1016) (xy -0.2794 -0.1016) (xy -0.2794 0.9906) (xy 0.2794 0.9906)
			)
			(stroke
				(width 0)
				(type default)
			)
			(fill no)
			(layer "B.CrtYd")
		)
		(fp_line
			(start 0.2794 0.9906)
			(end -0.2794 0.9906)
			(stroke
				(width 0.1)
				(type default)
			)
			(layer "B.Fab")
		)
		(fp_line
			(start 0.2794 -0.1016)
			(end 0.2794 0.9906)
			(stroke
				(width 0.1)
				(type default)
			)
			(layer "B.Fab")
		)
		(fp_line
			(start -0.2794 0.9906)
			(end -0.2794 -0.1016)
			(stroke
				(width 0.1)
				(type default)
			)
			(layer "B.Fab")
		)
		(fp_line
			(start -0.2794 -0.1016)
			(end 0.2794 -0.1016)
			(stroke
				(width 0.1)
				(type default)
			)
			(layer "B.Fab")
		)
		(pad "1" smd rect
			(at 0 0)
			(size 0.508 0.508)
			(layers "B.Cu" "B.Mask" "B.Paste")
			(net "SMB_CPU1_PE_HP_GTL_SCL")
		)
		(pad "2" smd rect
			(at 0 0.889)
			(size 0.508 0.508)
			(layers "B.Cu" "B.Mask" "B.Paste")
			(net "SMB_CPU1_PE_HP_GTL_R_SCL")
		)
		(zone
			(layer "B.Cu")
			(hatch none 0.5)
			(connect_pads
				(clearance 0)
			)
			(min_thickness 0.25)
			(keepout
				(tracks not_allowed)
				(vias allowed)
				(pads allowed)
				(copperpour not_allowed)
				(footprints allowed)
			)
			(placement
				(enabled no)
				(sheetname "")
			)
			(fill
				(thermal_gap 0.5)
				(thermal_bridge_width 0.5)
				(island_removal_mode 0)
			)
			(polygon
				(pts
					(xy 174.752 -89.281) (xy 175.26 -89.281) (xy 175.26 -88.9) (xy 174.752 -88.9)
				)
			)
		)
		(zone
			(layer "B.Cu")
			(hatch none 0.5)
			(connect_pads
				(clearance 0)
			)
			(min_thickness 0.25)
			(keepout
				(tracks allowed)
				(vias not_allowed)
				(pads allowed)
				(copperpour not_allowed)
				(footprints allowed)
			)
			(placement
				(enabled no)
				(sheetname "")
			)
			(fill
				(thermal_gap 0.5)
				(thermal_bridge_width 0.5)
				(island_removal_mode 0)
			)
			(polygon
				(pts
					(xy 174.752 -88.9) (xy 175.26 -88.9) (xy 175.26 -89.281) (xy 174.752 -89.281)
				)
			)
		)
	)
	(footprint ""
		(layer "B.Cu")
		(at 113.702592 -71.714614 180)
		(property "Reference" "C7P17"
			(at 0 0 0)
			(layer "B.SilkS")
			(hide yes)
			(effects
				(font
					(size 1.27 1.27)
				)
				(justify mirror)
			)
		)
		(property "Value" ""
			(at 0 0 0)
			(layer "B.Fab")
			(effects
				(font
					(size 1.27 1.27)
				)
				(justify mirror)
			)
		)
		(duplicate_pad_numbers_are_jumpers no)
		(fp_poly
			(pts
				(xy 0.7239 -0.2159) (xy -0.7239 -0.2159) (xy -0.7239 1.9939) (xy 0.7239 1.9939)
			)
			(stroke
				(width 0)
				(type default)
			)
			(fill no)
			(layer "B.CrtYd")
		)
		(fp_line
			(start 0.7239 1.9939)
			(end -0.7239 1.9939)
			(stroke
				(width 0.1)
				(type default)
			)
			(layer "B.Fab")
		)
		(fp_line
			(start 0.7239 -0.2159)
			(end 0.7239 1.9939)
			(stroke
				(width 0.1)
				(type default)
			)
			(layer "B.Fab")
		)
		(fp_line
			(start -0.7239 1.9939)
			(end -0.7239 -0.2159)
			(stroke
				(width 0.1)
				(type default)
			)
			(layer "B.Fab")
		)
		(fp_line
			(start -0.7239 -0.2159)
			(end 0.7239 -0.2159)
			(stroke
				(width 0.1)
				(type default)
			)
			(layer "B.Fab")
		)
		(pad "1" smd rect
			(at 0 0)
			(size 1.27 1.016)
			(layers "B.Cu" "B.Mask" "B.Paste")
			(net "PVCCIO_CPU1")
		)
		(pad "2" smd rect
			(at 0 1.778)
			(size 1.27 1.016)
			(layers "B.Cu" "B.Mask" "B.Paste")
			(net "GND")
		)
		(zone
			(layer "B.Cu")
			(hatch none 0.5)
			(connect_pads
				(clearance 0)
			)
			(min_thickness 0.25)
			(keepout
				(tracks not_allowed)
				(vias allowed)
				(pads allowed)
				(copperpour not_allowed)
				(footprints allowed)
			)
			(placement
				(enabled no)
				(sheetname "")
			)
			(fill
				(thermal_gap 0.5)
				(thermal_bridge_width 0.5)
				(island_removal_mode 0)
			)
			(polygon
				(pts
					(xy 113.067592 -72.222614) (xy 114.337592 -72.222614) (xy 114.337592 -72.984614) (xy 113.067592 -72.984614)
				)
			)
		)
	)
	(footprint ""
		(layer "B.Cu")
		(at 477.645222 -3.3782 -90)
		(property "Reference" "C9G9"
			(at 0 0 90)
			(layer "B.SilkS")
			(hide yes)
			(effects
				(font
					(size 1.27 1.27)
				)
				(justify mirror)
			)
		)
		(property "Value" ""
			(at 0 0 90)
			(layer "B.Fab")
			(effects
				(font
					(size 1.27 1.27)
				)
				(justify mirror)
			)
		)
		(duplicate_pad_numbers_are_jumpers no)
		(fp_poly
			(pts
				(xy -0.3048 -0.1016) (xy -0.3048 0.9906) (xy 0.3048 0.9906) (xy 0.3048 -0.1016)
			)
			(stroke
				(width 0)
				(type default)
			)
			(fill no)
			(layer "B.CrtYd")
		)
		(fp_line
			(start -0.3048 0.9906)
			(end -0.3048 -0.1016)
			(stroke
				(width 0.1)
				(type default)
			)
			(layer "B.Fab")
		)
		(fp_line
			(start 0.3048 0.9906)
			(end -0.3048 0.9906)
			(stroke
				(width 0.1)
				(type default)
			)
			(layer "B.Fab")
		)
		(fp_line
			(start -0.3048 -0.1016)
			(end 0.3048 -0.1016)
			(stroke
				(width 0.1)
				(type default)
			)
			(layer "B.Fab")
		)
		(fp_line
			(start 0.3048 -0.1016)
			(end 0.3048 0.9906)
			(stroke
				(width 0.1)
				(type default)
			)
			(layer "B.Fab")
		)
		(pad "1" smd rect
			(at 0 0 90)
			(size 0.508 0.508)
			(layers "B.Cu" "B.Mask" "B.Paste")
			(net "NIC_SER_P_MDI_3_DP")
		)
		(pad "2" smd rect
			(at 0 0.889 90)
			(size 0.508 0.508)
			(layers "B.Cu" "B.Mask" "B.Paste")
			(net "NIC_MDI_MNG_RX_DP")
		)
		(zone
			(layer "B.Cu")
			(hatch none 0.5)
			(connect_pads
				(clearance 0)
			)
			(min_thickness 0.25)
			(keepout
				(tracks not_allowed)
				(vias allowed)
				(pads allowed)
				(copperpour not_allowed)
				(footprints allowed)
			)
			(placement
				(enabled no)
				(sheetname "")
			)
			(fill
				(thermal_gap 0.5)
				(thermal_bridge_width 0.5)
				(island_removal_mode 0)
			)
			(polygon
				(pts
					(xy 477.010222 -3.1242) (xy 477.010222 -3.6322) (xy 477.391222 -3.6322) (xy 477.391222 -3.1242)
				)
			)
		)
		(zone
			(layer "B.Cu")
			(hatch none 0.5)
			(connect_pads
				(clearance 0)
			)
			(min_thickness 0.25)
			(keepout
				(tracks allowed)
				(vias not_allowed)
				(pads allowed)
				(copperpour not_allowed)
				(footprints allowed)
			)
			(placement
				(enabled no)
				(sheetname "")
			)
			(fill
				(thermal_gap 0.5)
				(thermal_bridge_width 0.5)
				(island_removal_mode 0)
			)
			(polygon
				(pts
					(xy 477.391222 -3.1242) (xy 477.391222 -3.6322) (xy 477.010222 -3.6322) (xy 477.010222 -3.1242)
				)
			)
		)
	)
)
